G04 ================== begin FILE IDENTIFICATION RECORD ==================*
G04 Layout Name:  D:/<user>/Wistron_project/16342-2/gbr/16342-2.brd*
G04 Film Name:    P_OUTLINE*
G04 File Format:  Gerber RS274X*
G04 File Origin:  Cadence Allegro 16.5-S056*
G04 Origin Date:  Mon Aug 07 11:24:00 2017*
G04 *
G04 Layer:  BOARD GEOMETRY/PANEL_OUTLINE*
G04 *
G04 Offset:    (0.00 0.00)*
G04 Mirror:    No*
G04 Mode:      Positive*
G04 Rotation:  0*
G04 FullContactRelief:  No*
G04 UndefLineWidth:     6.00*
G04 ================== end FILE IDENTIFICATION RECORD ====================*
%FSLAX35Y35*MOIN*%
%IR0*IPPOS*OFA0.00000B0.00000*MIA0B0*SFA1.00000B1.00000*%
%ADD10C,.006*%
G75*
%LPD*%
G75*
G54D10*
G01X3937Y0D02*
X116260D01*
G01X0Y3937D02*
G03X3937Y0I3937J0D01*
G01X0Y723480D02*
Y3937D01*
G01X416Y725241D02*
G03X0Y723480I3521J-1761D01*
G01X18597Y761603D02*
X416Y725241D01*
G01X22118Y763780D02*
G03X18597Y761603I1J-3937D01*
G01X386149Y763780D02*
X22118D01*
G01X120197Y3937D02*
Y429331D01*
G01X116260Y0D02*
G03X120197Y3937I0J3937D01*
G01X128071D02*
G03X132008Y0I3937J0D01*
G01X128071Y43308D02*
G03X120197I-3937J0D01*
G01X132008Y0D02*
X275709D01*
G01X128071Y3937D02*
Y43308D01*
G01X120197Y74016D02*
G03X128071I3937J0D01*
G01D02*
Y425394D01*
G01X124134Y433268D02*
X283583D01*
G01X124134D02*
G03X120197Y429331I0J-3937D01*
G01X188504Y425394D02*
X128071D01*
G01X152497Y21054D02*
G03I-4291J0D01*
G01X188504Y425394D02*
G03Y433268I0J3937D01*
G01X275709Y0D02*
G03X279646Y3937I0J3937D01*
G01X287520Y43308D02*
G03X279646I-3937J0D01*
G01Y3937D02*
Y43308D01*
G01Y74016D02*
G03X287520I3937J0D01*
G01X279646D02*
Y425394D01*
G01X265438Y405580D02*
G03I-4291J0D01*
G01X287520Y429331D02*
G03X283583Y433268I-3937J0D01*
G01X219213D02*
G03Y425394I0J-3937D01*
G01X279646D02*
X219213D01*
G01X291457Y0D02*
X921260D01*
G01X287520Y3937D02*
G03X291457Y0I3937J0D01*
G01X287520Y429331D02*
Y3937D01*
G01X408268Y188976D02*
Y723480D01*
G01Y188976D02*
G03X412205I1968J0D01*
G01X564173D02*
X412205D01*
G01X416142Y348379D02*
Y196851D01*
G01D02*
X560237D01*
G01X416142Y348379D02*
G03X408268I-3937J0D01*
G01Y379088D02*
G03X416142I3937J0D01*
G01Y688303D02*
Y379088D01*
G01Y688303D02*
G03X408268I-3937J0D01*
G01X389671Y761603D02*
G03X386149Y763780I-3522J-1760D01*
G01X407852Y725241D02*
X389671Y761603D01*
G01X408268Y723480D02*
G03X407852Y725241I-3937J0D01*
G01X524242Y763780D02*
X403757D01*
G01D02*
G03X400235Y758082I0J-3937D01*
G01X408268Y719012D02*
G03X416142I3937J0D01*
G01Y723480D02*
G03X414895Y728763I-11811J1D01*
G01X400235Y758082D02*
X414895Y728763D01*
G01X416142Y723480D02*
Y719012D01*
G01X490789Y356293D02*
G03I-4291J0D01*
G01X564173Y188976D02*
G03X568110I1968J0D01*
G01Y589622D02*
Y188976D01*
G01X560237Y261975D02*
Y196851D01*
G01X568111Y261975D02*
G03X560237I-3937J0D01*
G01Y292684D02*
G03X568111I3937J0D01*
G01X560237Y551040D02*
Y292684D01*
G01X568111Y551040D02*
G03X560237I-3937J0D01*
G01X568526Y591382D02*
G03X568110Y589622I3521J-1761D01*
G01X586707Y627745D02*
X568526Y591382D01*
G01X560237Y581748D02*
G03X568111I3937J0D01*
G01X561484Y594905D02*
G03X560237Y589622I10564J-5282D01*
G01D02*
Y581748D01*
G01X579665Y631267D02*
X561484Y594904D01*
G01X524242Y763780D02*
G03X532116I3937J0D01*
G01X834646D02*
X532116D01*
G01X590228Y629921D02*
G03X586707Y627745I0J-3937D01*
G01X842520Y629921D02*
X590228D01*
G01X590229Y637796D02*
G03X579665Y631268I0J-11812D01*
G01X590229Y637796D02*
X838583D01*
G01X842520Y629921D02*
G03X846457Y633858I0J3937D01*
G01Y759843D02*
Y633858D01*
G01X838583Y637796D02*
Y709449D01*
G01X850394Y763780D02*
G03X846457Y759843I0J-3937D01*
G01X903079Y763780D02*
X850394D01*
G01X812123Y734367D02*
G03I-4292J0D01*
G01X838583Y759843D02*
G03X834646Y763780I-3937J0D01*
G01X838583Y740158D02*
G03X846457I3937J0D01*
G01Y709449D02*
G03X838583I-3937J0D01*
G01Y740158D02*
Y759843D01*
G01X921260Y0D02*
G03X925197Y3937I0J3937D01*
G01D02*
Y723480D01*
G01X906600Y761603D02*
G03X903079Y763780I-3522J-1760D01*
G01X924781Y725241D02*
X906600Y761603D01*
G01X925197Y723480D02*
G03X924781Y725241I-3937J0D01*
M02*
